(kicad_sch (version 20230121) (generator eeschema)

  (paper "A3")

  (title_block
    (title "Kria K26 Devboard")
    (date "2024-03-26")
    (rev "1.2.5")
    (comment 1 "www.antmicro.com")
    (comment 2 "Antmicro Ltd.")
  )


  (wire (pts (xy 87.63 69.85) (xy 91.44 69.85))
    (stroke (width 0) (type default))
  )
  (polyline (pts (xy 153.67 93.98) (xy 157.48 93.98))
    (stroke (width 0) (type solid) (color 132 132 132 1))
  )

  (wire (pts (xy 91.44 77.47) (xy 87.63 77.47))
    (stroke (width 0) (type default))
  )
  (polyline (pts (xy 151.13 95.25) (xy 153.67 93.98))
    (stroke (width 0) (type solid) (color 132 132 132 1))
  )
  (polyline (pts (xy 151.13 92.71) (xy 151.13 95.25))
    (stroke (width 0) (type solid) (color 132 132 132 1))
  )

  (wire (pts (xy 125.73 68.58) (xy 125.73 88.9))
    (stroke (width 0) (type default))
  )
  (wire (pts (xy 87.63 74.93) (xy 91.44 74.93))
    (stroke (width 0) (type default))
  )
  (polyline (pts (xy 153.67 95.25) (xy 153.67 92.71))
    (stroke (width 0) (type solid) (color 132 132 132 1))
  )

  (wire (pts (xy 125.73 116.84) (xy 119.38 116.84))
    (stroke (width 0) (type default))
  )
  (polyline (pts (xy 151.13 92.71) (xy 153.67 93.98))
    (stroke (width 0) (type solid) (color 132 132 132 1))
  )

  (wire (pts (xy 87.63 72.39) (xy 91.44 72.39))
    (stroke (width 0) (type default))
  )
  (polyline (pts (xy 151.13 97.79) (xy 153.67 99.06))
    (stroke (width 0) (type solid) (color 132 132 132 1))
  )

  (bus (pts (xy 87.63 80.01) (xy 91.44 80.01))
    (stroke (width 0) (type default))
  )

  (polyline (pts (xy 151.13 87.63) (xy 153.67 88.9))
    (stroke (width 0) (type solid) (color 132 132 132 1))
  )
  (polyline (pts (xy 151.13 88.9) (xy 149.86 88.9))
    (stroke (width 0) (type solid) (color 132 132 132 1))
  )
  (polyline (pts (xy 151.13 93.98) (xy 149.86 93.98))
    (stroke (width 0) (type solid) (color 132 132 132 1))
  )
  (polyline (pts (xy 151.13 97.79) (xy 151.13 100.33))
    (stroke (width 0) (type solid) (color 132 132 132 1))
  )
  (polyline (pts (xy 153.67 88.9) (xy 156.21 88.9))
    (stroke (width 0) (type solid) (color 132 132 132 1))
  )
  (polyline (pts (xy 151.13 90.17) (xy 153.67 88.9))
    (stroke (width 0) (type solid) (color 132 132 132 1))
  )

  (wire (pts (xy 125.73 88.9) (xy 137.16 88.9))
    (stroke (width 0) (type default))
  )
  (polyline (pts (xy 153.67 90.17) (xy 153.67 87.63))
    (stroke (width 0) (type solid) (color 132 132 132 1))
  )
  (polyline (pts (xy 156.21 88.9) (xy 156.21 99.06))
    (stroke (width 0) (type solid) (color 132 132 132 1))
  )
  (polyline (pts (xy 151.13 99.06) (xy 149.86 99.06))
    (stroke (width 0) (type solid) (color 132 132 132 1))
  )

  (wire (pts (xy 125.73 99.06) (xy 125.73 116.84))
    (stroke (width 0) (type default))
  )
  (wire (pts (xy 119.38 68.58) (xy 125.73 68.58))
    (stroke (width 0) (type default))
  )
  (polyline (pts (xy 153.67 100.33) (xy 153.67 97.79))
    (stroke (width 0) (type solid) (color 132 132 132 1))
  )
  (polyline (pts (xy 151.13 100.33) (xy 153.67 99.06))
    (stroke (width 0) (type solid) (color 132 132 132 1))
  )
  (polyline (pts (xy 156.21 99.06) (xy 153.67 99.06))
    (stroke (width 0) (type solid) (color 132 132 132 1))
  )

  (wire (pts (xy 173.99 93.98) (xy 200.66 93.98))
    (stroke (width 0) (type default))
  )
  (wire (pts (xy 119.38 93.98) (xy 137.16 93.98))
    (stroke (width 0) (type default))
  )
  (wire (pts (xy 137.16 99.06) (xy 125.73 99.06))
    (stroke (width 0) (type default))
  )
  (bus (pts (xy 86.36 116.84) (xy 91.44 116.84))
    (stroke (width 0) (type default))
  )

  (wire (pts (xy 196.85 102.87) (xy 200.66 102.87))
    (stroke (width 0) (type default))
  )
  (wire (pts (xy 196.85 100.33) (xy 200.66 100.33))
    (stroke (width 0) (type default))
  )
  (wire (pts (xy 196.85 97.79) (xy 200.66 97.79))
    (stroke (width 0) (type default))
  )
  (polyline (pts (xy 151.13 87.63) (xy 151.13 90.17))
    (stroke (width 0) (type solid) (color 132 132 132 1))
  )

  (text "PoE" (at 106.68 121.92 0)
    (effects (font (size 1.27 1.27) (thickness 0.254) bold) (justify left bottom))
  )
  (text "Ideal diode" (at 148.59 102.87 0)
    (effects (font (size 1.27 1.27) (thickness 0.254) bold) (justify left bottom))
  )
  (text "DC/DC\nConverters" (at 210.82 90.17 0)
    (effects (font (size 1.27 1.27) (thickness 0.254) bold) (justify left bottom))
  )
  (text "USB-C" (at 106.68 76.2 0)
    (effects (font (size 1.27 1.27) (thickness 0.254) bold) (justify left bottom))
  )
  (text "DC Jack" (at 105.41 100.33 0)
    (effects (font (size 1.27 1.27) (thickness 0.254) bold) (justify left bottom))
  )

  (hierarchical_label "USBC_CC[1..2]" (shape input) (at 87.63 80.01 180) (fields_autoplaced)
    (effects (font (size 1.27 1.27)) (justify right))
  )
  (hierarchical_label "VCCOEN_PL_M2C" (shape input) (at 196.85 97.79 180) (fields_autoplaced)
    (effects (font (size 1.27 1.27)) (justify right))
  )
  (hierarchical_label "USBC_P" (shape input) (at 87.63 69.85 180) (fields_autoplaced)
    (effects (font (size 1.27 1.27)) (justify right))
  )
  (hierarchical_label "PS_ETH_EN" (shape input) (at 196.85 102.87 180) (fields_autoplaced)
    (effects (font (size 1.27 1.27)) (justify right))
  )
  (hierarchical_label "USBC_VBUS" (shape input) (at 87.63 74.93 180) (fields_autoplaced)
    (effects (font (size 1.27 1.27)) (justify right))
  )
  (hierarchical_label "POE_VC[1..4]" (shape output) (at 86.36 116.84 180) (fields_autoplaced)
    (effects (font (size 1.27 1.27)) (justify right))
  )
  (hierarchical_label "PD_EN" (shape input) (at 87.63 77.47 180) (fields_autoplaced)
    (effects (font (size 1.27 1.27)) (justify right))
  )
  (hierarchical_label "USBC_N" (shape input) (at 87.63 72.39 180) (fields_autoplaced)
    (effects (font (size 1.27 1.27)) (justify right))
  )
  (hierarchical_label "VCCOEN_PS_M2C" (shape input) (at 196.85 100.33 180) (fields_autoplaced)
    (effects (font (size 1.27 1.27)) (justify right))
  )

  (sheet (at 200.66 85.09) (size 30.48 19.05) (fields_autoplaced)
    (stroke (width 0) (type solid))
    (fill (color 0 0 0 0.0000))
    (property "Sheetname" "DC/DC conventers" (at 200.66 84.3784 0)
      (effects (font (size 1.27 1.27)) (justify left bottom))
    )
    (property "Sheetfile" "dc-dc-conventers.kicad_sch" (at 200.66 104.7246 0)
      (effects (font (size 1.27 1.27)) (justify left top))
    )
    (pin "DC_MAIN_BUS" input (at 200.66 93.98 180)
      (effects (font (size 1.27 1.27)) (justify left))
    )
    (pin "VCCOEN_PS_M2C" input (at 200.66 100.33 180)
      (effects (font (size 1.27 1.27)) (justify left))
    )
    (pin "VCCOEN_PL_M2C" input (at 200.66 97.79 180)
      (effects (font (size 1.27 1.27)) (justify left))
    )
    (pin "PS_ETH_EN" input (at 200.66 102.87 180)
      (effects (font (size 1.27 1.27)) (justify left))
    )
    (instances
      (project "kria-k26-devboard"
        (path "" (page "7"))
      )
    )
  )

  (sheet (at 91.44 114.3) (size 27.94 13.97) (fields_autoplaced)
    (stroke (width 0) (type solid))
    (fill (color 0 0 0 0.0000))
    (property "Sheetname" "PoE" (at 91.44 113.5884 0)
      (effects (font (size 1.27 1.27)) (justify left bottom))
    )
    (property "Sheetfile" "PoE.kicad_sch" (at 91.44 128.8546 0)
      (effects (font (size 1.27 1.27)) (justify left top))
    )
    (pin "POE_12V" output (at 119.38 116.84 0)
      (effects (font (size 1.27 1.27)) (justify right))
    )
    (pin "POE_VC[1..4]" output (at 91.44 116.84 180)
      (effects (font (size 1.27 1.27)) (justify left))
    )
    (instances
      (project "kria-k26-devboard"
        (path "" (page "5"))
      )
    )
  )

  (sheet (at 137.16 85.09) (size 36.83 19.05) (fields_autoplaced)
    (stroke (width 0) (type solid))
    (fill (color 0 0 0 0.0000))
    (property "Sheetname" "Supply ORing" (at 137.16 84.3784 0)
      (effects (font (size 1.27 1.27)) (justify left bottom))
    )
    (property "Sheetfile" "supply-oring.kicad_sch" (at 137.16 104.7246 0)
      (effects (font (size 1.27 1.27)) (justify left top))
    )
    (pin "DC_IN" input (at 137.16 93.98 180)
      (effects (font (size 1.27 1.27)) (justify left))
    )
    (pin "POE_12V" input (at 137.16 99.06 180)
      (effects (font (size 1.27 1.27)) (justify left))
    )
    (pin "DC_MAIN_BUS" output (at 173.99 93.98 0)
      (effects (font (size 1.27 1.27)) (justify right))
    )
    (pin "PD_VBUS" input (at 137.16 88.9 180)
      (effects (font (size 1.27 1.27)) (justify left))
    )
    (instances
      (project "kria-k26-devboard"
        (path "" (page "6"))
      )
    )
  )

  (sheet (at 91.44 67.31) (size 27.94 15.24) (fields_autoplaced)
    (stroke (width 0) (type solid))
    (fill (color 0 0 0 0.0000))
    (property "Sheetname" "USB-C socket" (at 91.44 66.5984 0)
      (effects (font (size 1.27 1.27)) (justify left bottom))
    )
    (property "Sheetfile" "usbc-socket.kicad_sch" (at 91.44 83.1346 0)
      (effects (font (size 1.27 1.27)) (justify left top))
    )
    (pin "USBC_CC[1..2]" input (at 91.44 80.01 180)
      (effects (font (size 1.27 1.27)) (justify left))
    )
    (pin "USBC_P" input (at 91.44 69.85 180)
      (effects (font (size 1.27 1.27)) (justify left))
    )
    (pin "USBC_N" input (at 91.44 72.39 180)
      (effects (font (size 1.27 1.27)) (justify left))
    )
    (pin "USBC_VBUS" output (at 91.44 74.93 180)
      (effects (font (size 1.27 1.27)) (justify left))
    )
    (pin "PD_VBUS" output (at 119.38 68.58 0)
      (effects (font (size 1.27 1.27)) (justify right))
    )
    (pin "PD_EN" input (at 91.44 77.47 180)
      (effects (font (size 1.27 1.27)) (justify left))
    )
    (instances
      (project "kria-k26-devboard"
        (path "" (page "3"))
      )
    )
  )

  (sheet (at 91.44 91.44) (size 27.94 15.24) (fields_autoplaced)
    (stroke (width 0) (type solid))
    (fill (color 0 0 0 0.0000))
    (property "Sheetname" "DC Input" (at 91.44 90.7284 0)
      (effects (font (size 1.27 1.27)) (justify left bottom))
    )
    (property "Sheetfile" "dc-input.kicad_sch" (at 91.44 107.2646 0)
      (effects (font (size 1.27 1.27)) (justify left top))
    )
    (pin "DC_IN" output (at 119.38 93.98 0)
      (effects (font (size 1.27 1.27)) (justify right))
    )
    (instances
      (project "kria-k26-devboard"
        (path "" (page "4"))
      )
    )
  )
)
